(kicad_pcb
	(version 20260206)
	(generator "pcbnew")
	(generator_version "10.0")
	(general
		(thickness 1.6)
		(legacy_teardrops no)
	)
	(paper "A4")
	(title_block
		(title "01162023_DA0F0TEBIF0_F0T_Expander_BD_F_brd_V02_OCP.brd")
		(comment 1 "Grand Teton / footprints 2774-2779 of 9728")
	)
	(layers
		(0 "F.Cu" signal "TOP")
		(4 "In1.Cu" signal "GND")
		(6 "In2.Cu" signal "VCC")
		(8 "In3.Cu" signal "VCC1")
		(10 "In4.Cu" signal "GND1")
		(12 "In5.Cu" signal "IN1")
		(14 "In6.Cu" signal "GND2")
		(16 "In7.Cu" signal "IN2")
		(18 "In8.Cu" signal "GND3")
		(20 "In9.Cu" signal "IN3")
		(22 "In10.Cu" signal "GND4")
		(24 "In11.Cu" signal "IN4")
		(26 "In12.Cu" signal "GND5")
		(28 "In13.Cu" signal "IN5")
		(30 "In14.Cu" signal "GND6")
		(32 "In15.Cu" signal "IN6")
		(34 "In16.Cu" signal "GND7")
		(2 "B.Cu" signal "BOTTOM")
		(9 "F.Adhes" user "F.Adhesive")
		(11 "B.Adhes" user "B.Adhesive")
		(13 "F.Paste" user "Package Geometry/Pastemask Top")
		(15 "B.Paste" user "Package Geometry/Pastemask Bottom")
		(5 "F.SilkS" user "Ref Des/Silkscreen Top")
		(7 "B.SilkS" user "Ref Des/Silkscreen Bottom")
		(1 "F.Mask" user "Board Geometry/Soldermask Top")
		(3 "B.Mask" user "Board Geometry/Soldermask Bottom")
		(17 "Dwgs.User" user "User.Drawings")
		(19 "Cmts.User" user "User.Comments")
		(21 "Eco1.User" user "User.Eco1")
		(23 "Eco2.User" user "User.Eco2")
		(25 "Edge.Cuts" user "Board Geometry/Outline")
		(27 "Margin" user)
		(31 "F.CrtYd" user "Package Geometry/Place Bound Top")
		(29 "B.CrtYd" user "Package Geometry/Place Bound Bottom")
		(35 "F.Fab" user "Ref Des/Assembly Top")
		(33 "B.Fab" user "Ref Des/Assembly Bottom")
	)
	(footprint ""
		(layer "F.Cu")
		(at 189.382654 -80.739742)
		(property "Reference" "R203"
			(at 0 0 0)
			(layer "F.SilkS")
			(hide yes)
			(effects
				(font
					(size 1.27 1.27)
				)
			)
		)
		(property "Value" ""
			(at 0 0 0)
			(layer "F.Fab")
			(effects
				(font
					(size 1.27 1.27)
				)
			)
		)
		(duplicate_pad_numbers_are_jumpers no)
		(fp_line
			(start -0.7874 -0.4064)
			(end 0.7874 -0.4064)
			(stroke
				(width 0.1524)
				(type default)
			)
			(layer "F.SilkS")
		)
		(fp_line
			(start -0.7874 0.4064)
			(end -0.7874 -0.4064)
			(stroke
				(width 0.1524)
				(type default)
			)
			(layer "F.SilkS")
		)
		(fp_line
			(start 0.7874 -0.4064)
			(end 0.7874 0.4064)
			(stroke
				(width 0.1524)
				(type default)
			)
			(layer "F.SilkS")
		)
		(fp_line
			(start 0.7874 0.4064)
			(end -0.7874 0.4064)
			(stroke
				(width 0.1524)
				(type default)
			)
			(layer "F.SilkS")
		)
		(fp_line
			(start -0.67945 -0.305054)
			(end -0.12065 -0.305054)
			(stroke
				(width 0.1)
				(type default)
			)
			(layer "F.Fab")
		)
		(fp_line
			(start -0.67945 0.3048)
			(end -0.67945 -0.305054)
			(stroke
				(width 0.1)
				(type default)
			)
			(layer "F.Fab")
		)
		(fp_line
			(start -0.12065 -0.305054)
			(end -0.12065 -0.2794)
			(stroke
				(width 0.1)
				(type default)
			)
			(layer "F.Fab")
		)
		(fp_line
			(start -0.12065 -0.2794)
			(end 0.12065 -0.2794)
			(stroke
				(width 0.1)
				(type default)
			)
			(layer "F.Fab")
		)
		(fp_line
			(start -0.12065 0.2794)
			(end -0.12065 0.3048)
			(stroke
				(width 0.1)
				(type default)
			)
			(layer "F.Fab")
		)
		(fp_line
			(start -0.12065 0.3048)
			(end -0.67945 0.3048)
			(stroke
				(width 0.1)
				(type default)
			)
			(layer "F.Fab")
		)
		(fp_line
			(start 0.120396 0.2794)
			(end -0.12065 0.2794)
			(stroke
				(width 0.1)
				(type default)
			)
			(layer "F.Fab")
		)
		(fp_line
			(start 0.120396 0.3048)
			(end 0.120396 0.2794)
			(stroke
				(width 0.1)
				(type default)
			)
			(layer "F.Fab")
		)
		(fp_line
			(start 0.12065 -0.3048)
			(end 0.67945 -0.3048)
			(stroke
				(width 0.1)
				(type default)
			)
			(layer "F.Fab")
		)
		(fp_line
			(start 0.12065 -0.2794)
			(end 0.12065 -0.3048)
			(stroke
				(width 0.1)
				(type default)
			)
			(layer "F.Fab")
		)
		(fp_line
			(start 0.67945 -0.3048)
			(end 0.67945 0.3048)
			(stroke
				(width 0.1)
				(type default)
			)
			(layer "F.Fab")
		)
		(fp_line
			(start 0.67945 0.3048)
			(end 0.120396 0.3048)
			(stroke
				(width 0.1)
				(type default)
			)
			(layer "F.Fab")
		)
		(pad "1" smd circle
			(at -0.40005 0)
			(size 0 0)
			(layers "F.Cu" "F.Mask" "F.Paste")
			(net "P3V3_AUX")
		)
		(pad "2" smd circle
			(at 0.40005 0)
			(size 0 0)
			(layers "F.Cu" "F.Mask" "F.Paste")
			(net "HP_NIC3_HSC_PWRGD_N")
		)
	)
	(footprint ""
		(layer "F.Cu")
		(at 35.766248 -356.244906 90)
		(property "Reference" "C176"
			(at 0 0 90)
			(layer "F.SilkS")
			(hide yes)
			(effects
				(font
					(size 1.27 1.27)
				)
			)
		)
		(property "Value" ""
			(at 0 0 90)
			(layer "F.Fab")
			(effects
				(font
					(size 1.27 1.27)
				)
			)
		)
		(duplicate_pad_numbers_are_jumpers no)
		(fp_line
			(start 0.299974 -0.150114)
			(end 0.299974 0.150114)
			(stroke
				(width 0.1)
				(type default)
			)
			(layer "F.Fab")
		)
		(fp_line
			(start -0.299974 -0.150114)
			(end 0.299974 -0.150114)
			(stroke
				(width 0.1)
				(type default)
			)
			(layer "F.Fab")
		)
		(fp_line
			(start 0.299974 0.150114)
			(end -0.299974 0.150114)
			(stroke
				(width 0.1)
				(type default)
			)
			(layer "F.Fab")
		)
		(fp_line
			(start -0.299974 0.150114)
			(end -0.299974 -0.150114)
			(stroke
				(width 0.1)
				(type default)
			)
			(layer "F.Fab")
		)
		(pad "1" smd rect
			(at -0.2667 0 90)
			(size 0.3048 0.381)
			(layers "F.Cu" "F.Mask" "F.Paste")
			(net "P5E_PEX0_STN7_TX_DN<120>")
		)
		(pad "2" smd rect
			(at 0.2667 0 90)
			(size 0.3048 0.381)
			(layers "F.Cu" "F.Mask" "F.Paste")
			(net "P5E_PEX0_STN7_TX_C_DN<120>")
		)
	)
	(footprint ""
		(layer "F.Cu")
		(at 29.357828 -27.006296 -90)
		(property "Reference" "PR6921"
			(at 0 0 270)
			(layer "F.SilkS")
			(hide yes)
			(effects
				(font
					(size 1.27 1.27)
				)
			)
		)
		(property "Value" ""
			(at 0 0 270)
			(layer "F.Fab")
			(effects
				(font
					(size 1.27 1.27)
				)
			)
		)
		(duplicate_pad_numbers_are_jumpers no)
		(fp_line
			(start -0.7874 0.4064)
			(end -0.7874 -0.4064)
			(stroke
				(width 0.1524)
				(type default)
			)
			(layer "F.SilkS")
		)
		(fp_line
			(start 0.7874 0.4064)
			(end -0.7874 0.4064)
			(stroke
				(width 0.1524)
				(type default)
			)
			(layer "F.SilkS")
		)
		(fp_line
			(start -0.7874 -0.4064)
			(end 0.7874 -0.4064)
			(stroke
				(width 0.1524)
				(type default)
			)
			(layer "F.SilkS")
		)
		(fp_line
			(start 0.7874 -0.4064)
			(end 0.7874 0.4064)
			(stroke
				(width 0.1524)
				(type default)
			)
			(layer "F.SilkS")
		)
		(fp_line
			(start -0.67945 0.3048)
			(end -0.67945 -0.305054)
			(stroke
				(width 0.1)
				(type default)
			)
			(layer "F.Fab")
		)
		(fp_line
			(start -0.12065 0.3048)
			(end -0.67945 0.3048)
			(stroke
				(width 0.1)
				(type default)
			)
			(layer "F.Fab")
		)
		(fp_line
			(start 0.120396 0.3048)
			(end 0.120396 0.2794)
			(stroke
				(width 0.1)
				(type default)
			)
			(layer "F.Fab")
		)
		(fp_line
			(start 0.67945 0.3048)
			(end 0.120396 0.3048)
			(stroke
				(width 0.1)
				(type default)
			)
			(layer "F.Fab")
		)
		(fp_line
			(start -0.12065 0.2794)
			(end -0.12065 0.3048)
			(stroke
				(width 0.1)
				(type default)
			)
			(layer "F.Fab")
		)
		(fp_line
			(start 0.120396 0.2794)
			(end -0.12065 0.2794)
			(stroke
				(width 0.1)
				(type default)
			)
			(layer "F.Fab")
		)
		(fp_line
			(start -0.12065 -0.2794)
			(end 0.12065 -0.2794)
			(stroke
				(width 0.1)
				(type default)
			)
			(layer "F.Fab")
		)
		(fp_line
			(start 0.12065 -0.2794)
			(end 0.12065 -0.3048)
			(stroke
				(width 0.1)
				(type default)
			)
			(layer "F.Fab")
		)
		(fp_line
			(start 0.12065 -0.3048)
			(end 0.67945 -0.3048)
			(stroke
				(width 0.1)
				(type default)
			)
			(layer "F.Fab")
		)
		(fp_line
			(start 0.67945 -0.3048)
			(end 0.67945 0.3048)
			(stroke
				(width 0.1)
				(type default)
			)
			(layer "F.Fab")
		)
		(fp_line
			(start -0.67945 -0.305054)
			(end -0.12065 -0.305054)
			(stroke
				(width 0.1)
				(type default)
			)
			(layer "F.Fab")
		)
		(fp_line
			(start -0.12065 -0.305054)
			(end -0.12065 -0.2794)
			(stroke
				(width 0.1)
				(type default)
			)
			(layer "F.Fab")
		)
		(pad "1" smd circle
			(at -0.40005 0 270)
			(size 0 0)
			(layers "F.Cu" "F.Mask" "F.Paste")
			(net "P3V3_SSD1_CO_MODE")
		)
		(pad "2" smd circle
			(at 0.40005 0 270)
			(size 0 0)
			(layers "F.Cu" "F.Mask" "F.Paste")
			(net "GND")
		)
	)
	(footprint ""
		(layer "F.Cu")
		(at 447.676778 -209.393282)
		(property "Reference" "R1001"
			(at 0 0 0)
			(layer "F.SilkS")
			(hide yes)
			(effects
				(font
					(size 1.27 1.27)
				)
			)
		)
		(property "Value" ""
			(at 0 0 0)
			(layer "F.Fab")
			(effects
				(font
					(size 1.27 1.27)
				)
			)
		)
		(duplicate_pad_numbers_are_jumpers no)
		(fp_line
			(start -0.7874 -0.4064)
			(end 0.7874 -0.4064)
			(stroke
				(width 0.1524)
				(type default)
			)
			(layer "F.SilkS")
		)
		(fp_line
			(start -0.67945 -0.305054)
			(end -0.12065 -0.305054)
			(stroke
				(width 0.1)
				(type default)
			)
			(layer "F.Fab")
		)
		(fp_line
			(start -0.67945 0.3048)
			(end -0.67945 -0.305054)
			(stroke
				(width 0.1)
				(type default)
			)
			(layer "F.Fab")
		)
		(fp_line
			(start -0.12065 -0.305054)
			(end -0.12065 -0.2794)
			(stroke
				(width 0.1)
				(type default)
			)
			(layer "F.Fab")
		)
		(fp_line
			(start -0.12065 -0.2794)
			(end 0.12065 -0.2794)
			(stroke
				(width 0.1)
				(type default)
			)
			(layer "F.Fab")
		)
		(fp_line
			(start -0.12065 0.2794)
			(end -0.12065 0.3048)
			(stroke
				(width 0.1)
				(type default)
			)
			(layer "F.Fab")
		)
		(fp_line
			(start -0.12065 0.3048)
			(end -0.67945 0.3048)
			(stroke
				(width 0.1)
				(type default)
			)
			(layer "F.Fab")
		)
		(fp_line
			(start 0.120396 0.2794)
			(end -0.12065 0.2794)
			(stroke
				(width 0.1)
				(type default)
			)
			(layer "F.Fab")
		)
		(fp_line
			(start 0.120396 0.3048)
			(end 0.120396 0.2794)
			(stroke
				(width 0.1)
				(type default)
			)
			(layer "F.Fab")
		)
		(fp_line
			(start 0.12065 -0.3048)
			(end 0.67945 -0.3048)
			(stroke
				(width 0.1)
				(type default)
			)
			(layer "F.Fab")
		)
		(fp_line
			(start 0.12065 -0.2794)
			(end 0.12065 -0.3048)
			(stroke
				(width 0.1)
				(type default)
			)
			(layer "F.Fab")
		)
		(fp_line
			(start 0.67945 -0.3048)
			(end 0.67945 0.3048)
			(stroke
				(width 0.1)
				(type default)
			)
			(layer "F.Fab")
		)
		(fp_line
			(start 0.67945 0.3048)
			(end 0.120396 0.3048)
			(stroke
				(width 0.1)
				(type default)
			)
			(layer "F.Fab")
		)
		(pad "1" smd circle
			(at -0.40005 0)
			(size 0 0)
			(layers "F.Cu" "F.Mask" "F.Paste")
			(net "USB2_MICRO_DP")
		)
		(pad "2" smd circle
			(at 0.40005 0)
			(size 0 0)
			(layers "F.Cu" "F.Mask" "F.Paste")
			(net "USB2_FT4232_MUX_D_DP")
		)
	)
	(footprint ""
		(layer "F.Cu")
		(at 163.985702 -27.092148 -90)
		(property "Reference" "R5741"
			(at 0 0 270)
			(layer "F.SilkS")
			(hide yes)
			(effects
				(font
					(size 1.27 1.27)
				)
			)
		)
		(property "Value" ""
			(at 0 0 270)
			(layer "F.Fab")
			(effects
				(font
					(size 1.27 1.27)
				)
			)
		)
		(duplicate_pad_numbers_are_jumpers no)
		(fp_line
			(start -0.7874 0.4064)
			(end -0.7874 -0.4064)
			(stroke
				(width 0.1524)
				(type default)
			)
			(layer "F.SilkS")
		)
		(fp_line
			(start 0.7874 0.4064)
			(end -0.7874 0.4064)
			(stroke
				(width 0.1524)
				(type default)
			)
			(layer "F.SilkS")
		)
		(fp_line
			(start -0.7874 -0.4064)
			(end 0.7874 -0.4064)
			(stroke
				(width 0.1524)
				(type default)
			)
			(layer "F.SilkS")
		)
		(fp_line
			(start 0.7874 -0.4064)
			(end 0.7874 0.4064)
			(stroke
				(width 0.1524)
				(type default)
			)
			(layer "F.SilkS")
		)
		(fp_line
			(start -0.67945 0.3048)
			(end -0.67945 -0.305054)
			(stroke
				(width 0.1)
				(type default)
			)
			(layer "F.Fab")
		)
		(fp_line
			(start -0.12065 0.3048)
			(end -0.67945 0.3048)
			(stroke
				(width 0.1)
				(type default)
			)
			(layer "F.Fab")
		)
		(fp_line
			(start 0.120396 0.3048)
			(end 0.120396 0.2794)
			(stroke
				(width 0.1)
				(type default)
			)
			(layer "F.Fab")
		)
		(fp_line
			(start 0.67945 0.3048)
			(end 0.120396 0.3048)
			(stroke
				(width 0.1)
				(type default)
			)
			(layer "F.Fab")
		)
		(fp_line
			(start -0.12065 0.2794)
			(end -0.12065 0.3048)
			(stroke
				(width 0.1)
				(type default)
			)
			(layer "F.Fab")
		)
		(fp_line
			(start 0.120396 0.2794)
			(end -0.12065 0.2794)
			(stroke
				(width 0.1)
				(type default)
			)
			(layer "F.Fab")
		)
		(fp_line
			(start -0.12065 -0.2794)
			(end 0.12065 -0.2794)
			(stroke
				(width 0.1)
				(type default)
			)
			(layer "F.Fab")
		)
		(fp_line
			(start 0.12065 -0.2794)
			(end 0.12065 -0.3048)
			(stroke
				(width 0.1)
				(type default)
			)
			(layer "F.Fab")
		)
		(fp_line
			(start 0.12065 -0.3048)
			(end 0.67945 -0.3048)
			(stroke
				(width 0.1)
				(type default)
			)
			(layer "F.Fab")
		)
		(fp_line
			(start 0.67945 -0.3048)
			(end 0.67945 0.3048)
			(stroke
				(width 0.1)
				(type default)
			)
			(layer "F.Fab")
		)
		(fp_line
			(start -0.67945 -0.305054)
			(end -0.12065 -0.305054)
			(stroke
				(width 0.1)
				(type default)
			)
			(layer "F.Fab")
		)
		(fp_line
			(start -0.12065 -0.305054)
			(end -0.12065 -0.2794)
			(stroke
				(width 0.1)
				(type default)
			)
			(layer "F.Fab")
		)
		(pad "1" smd circle
			(at -0.40005 0 270)
			(size 0 0)
			(layers "F.Cu" "F.Mask" "F.Paste")
			(net "P3V3_SSD5")
		)
		(pad "2" smd circle
			(at 0.40005 0 270)
			(size 0 0)
			(layers "F.Cu" "F.Mask" "F.Paste")
			(net "SSD5_LED_ISO_N")
		)
	)
	(footprint ""
		(layer "F.Cu")
		(at 19.652488 -171.392596 90)
		(property "Reference" "PU4"
			(at -0.807466 1.632712 0)
			(unlocked yes)
			(layer "F.SilkS")
			(effects
				(font
					(size 0.7874 0.5842)
					(thickness 0.1524)
				)
				(justify left)
			)
		)
		(property "Value" ""
			(at 0 0 90)
			(layer "F.Fab")
			(effects
				(font
					(size 1.27 1.27)
				)
			)
		)
		(duplicate_pad_numbers_are_jumpers no)
		(fp_line
			(start 1.55829 -1.02489)
			(end -1.55829 -1.02489)
			(stroke
				(width 0.1524)
				(type default)
			)
			(layer "F.SilkS")
		)
		(fp_line
			(start -1.55829 -1.02489)
			(end -1.55829 1.02489)
			(stroke
				(width 0.1524)
				(type default)
			)
			(layer "F.SilkS")
		)
		(fp_line
			(start 1.55829 1.02489)
			(end 1.55829 -1.02489)
			(stroke
				(width 0.1524)
				(type default)
			)
			(layer "F.SilkS")
		)
		(fp_line
			(start -1.55829 1.02489)
			(end 1.55829 1.02489)
			(stroke
				(width 0.1524)
				(type default)
			)
			(layer "F.SilkS")
		)
		(fp_poly
			(pts
				(xy -1.243076 -1.110996) (xy -1.759712 -1.283208) (xy -1.415288 -1.627632)
			)
			(stroke
				(width 0)
				(type default)
			)
			(fill yes)
			(layer "F.SilkS")
		)
		(fp_line
			(start 1.02489 -1.02489)
			(end -1.02489 -1.02489)
			(stroke
				(width 0.1)
				(type default)
			)
			(layer "F.Fab")
		)
		(fp_line
			(start -1.02489 -1.02489)
			(end -1.02489 1.02489)
			(stroke
				(width 0.1)
				(type default)
			)
			(layer "F.Fab")
		)
		(fp_line
			(start 1.02489 1.02489)
			(end 1.02489 -1.02489)
			(stroke
				(width 0.1)
				(type default)
			)
			(layer "F.Fab")
		)
		(fp_line
			(start -1.02489 1.02489)
			(end 1.02489 1.02489)
			(stroke
				(width 0.1)
				(type default)
			)
			(layer "F.Fab")
		)
		(fp_poly
			(pts
				(xy -1.682496 -0.750062) (xy -2.279904 -0.451104) (xy -2.279904 -1.048766)
			)
			(stroke
				(width 0)
				(type default)
			)
			(fill yes)
			(layer "F.Fab")
		)
		(pad "1" smd rect
			(at -0.999998 -0.750062)
			(size 0.2794 0.8128)
			(layers "F.Cu" "F.Mask" "F.Paste")
			(net "SW_P5V_AUX_PH")
		)
		(pad "2" smd rect
			(at -0.999998 -0.249936)
			(size 0.2794 0.8128)
			(layers "F.Cu" "F.Mask" "F.Paste")
			(net "SW_P12V_P5V_AUX_FLT")
		)
		(pad "3" smd rect
			(at -0.999998 0.249936)
			(size 0.2794 0.8128)
			(layers "F.Cu" "F.Mask" "F.Paste")
			(net "SW_P5V_AUX_BT")
		)
		(pad "4" smd rect
			(at -0.999998 0.750062)
			(size 0.2794 0.8128)
			(layers "F.Cu" "F.Mask" "F.Paste")
			(net "P5V_AUX_EN")
		)
		(pad "5" smd rect
			(at 0.999998 0.750062)
			(size 0.2794 0.8128)
			(layers "F.Cu" "F.Mask" "F.Paste")
			(net "P5V_AUX_FB")
		)
		(pad "6" smd rect
			(at 0.999998 0.249936)
			(size 0.2794 0.8128)
			(layers "F.Cu" "F.Mask" "F.Paste")
			(net "PWRGD_P5V_AUX")
		)
		(pad "7" smd rect
			(at 0.999998 -0.249936)
			(size 0.2794 0.8128)
			(layers "F.Cu" "F.Mask" "F.Paste")
			(net "GND")
		)
		(pad "8" smd rect
			(at 0.999998 -0.750062)
			(size 0.2794 0.8128)
			(layers "F.Cu" "F.Mask" "F.Paste")
			(net "GND")
		)
		(pad "TH" smd rect
			(at 0 0 90)
			(size 0.7112 1.3208)
			(layers "F.Cu" "F.Mask" "F.Paste")
			(net "GND")
		)
		(zone
			(layer "F.Cu")
			(hatch none 0.5)
			(connect_pads
				(clearance 0)
			)
			(min_thickness 0.25)
			(keepout
				(tracks not_allowed)
				(vias allowed)
				(pads allowed)
				(copperpour not_allowed)
				(footprints allowed)
			)
			(placement
				(enabled no)
				(sheetname "")
			)
			(fill
				(thermal_gap 0.5)
				(thermal_bridge_width 0.5)
				(island_removal_mode 0)
			)
			(polygon
				(pts
					(xy 18.636488 -171.925996) (xy 20.668488 -171.925996) (xy 20.668488 -170.859196) (xy 18.636488 -170.859196)
					(xy 18.636488 -171.748196) (xy 18.941288 -171.748196) (xy 18.941288 -170.986196) (xy 20.363688 -170.986196)
					(xy 20.363688 -171.798996) (xy 18.941288 -171.798996) (xy 18.941288 -171.773596) (xy 18.636488 -171.773596)
				)
			)
		)
	)
)
